G04 ================== begin FILE IDENTIFICATION RECORD ==================*
G04 Layout Name:  17301-sa.brd*
G04 Film Name:    BSILK*
G04 File Format:  Gerber RS274X*
G04 File Origin:  Cadence Allegro 16.6-2015-S079*
G04 Origin Date:  Thu Jun 22 17:49:47 2017*
G04 *
G04 Layer:  REF DES/ASSEMBLY_BOTTOM*
G04 Layer:  PACKAGE GEOMETRY/SILKSCREEN_BOTTOM*
G04 Layer:  DRAWING FORMAT/LAYER_SILK_B*
G04 Layer:  BOARD GEOMETRY/SILKSCREEN_BOTTOM*
G04 Layer:  VIA CLASS/FILMMASKBOTTOM*
G04 Layer:  DRAWING FORMAT/LAYER_PCB_STORY*
G04 *
G04 Offset:    (0.00 0.00)*
G04 Mirror:    No*
G04 Mode:      Positive*
G04 Rotation:  0*
G04 FullContactRelief:  No*
G04 UndefLineWidth:     6.00*
G04 ================== end FILE IDENTIFICATION RECORD ====================*
%FSLAX35Y35*MOIN*%
%IR0*IPPOS*OFA0.00000B0.00000*MIA0B0*SFA1.00000B1.00000*%
%ADD10C,.02*%
%ADD11C,.012*%
%ADD12C,.013*%
%ADD13C,.015*%
%ADD14C,.016*%
%ADD15C,.019*%
%ADD16C,.006*%
%ADD17C,.008*%
G75*
%LPD*%
G75*
G36*
G01X36585Y37562D02*
X40085D01*
Y22085D01*
X50774D01*
Y82639D01*
X40085D01*
Y67162D01*
X36585D01*
Y37562D01*
G37*
G36*
G01X59171Y79994D02*
X61671Y82494D01*
Y77494D01*
X59171Y79994D01*
G37*
G36*
G01X271900Y53700D02*
X283100D01*
Y36300D01*
X271900D01*
Y53700D01*
G37*
G36*
G01X288092Y75110D02*
X285592Y72610D01*
Y77610D01*
X288092Y75110D01*
G37*
G36*
G01X319000Y29900D02*
X320400Y28500D01*
X317600D01*
X319000Y29900D01*
G37*
G36*
G01X312344Y58492D02*
X311144Y57292D01*
X312344Y56092D01*
Y58492D01*
G37*
G36*
G01X318956Y74418D02*
X311358D01*
Y99440D01*
X318956D01*
Y74418D01*
G37*
G36*
G01X305058D02*
X300728D01*
Y99440D01*
X305058D01*
Y74418D01*
G37*
G36*
G01X313400Y148300D02*
X324600D01*
Y165750D01*
X313400D01*
Y148300D01*
G37*
G36*
G01X313531Y204754D02*
X324731D01*
Y187354D01*
X313531D01*
Y204754D01*
G37*
G36*
G01X343031Y35854D02*
X354231D01*
Y53304D01*
X343031D01*
Y35854D01*
G37*
G36*
G01X329586Y74418D02*
X325256D01*
Y99440D01*
X329586D01*
Y74418D01*
G37*
G54D10*
G01X-139981Y-146685D02*
G02I-12000J0D01*
G01X-145131D02*
G02I-6850J0D01*
G01X-135981D02*
X-167981D01*
G01X-135981Y-162685D02*
Y-242685D01*
G01D02*
X971619D01*
G01X-135981Y-198185D02*
X971619D01*
G01X-151981Y-162685D02*
Y-130685D01*
G01X-135981Y-162685D02*
X971619D01*
G01X184119D02*
Y-242685D01*
G01X321619Y-162685D02*
Y-242685D01*
G01X313024Y59703D02*
Y53703D01*
G01X332000Y138500D02*
Y144500D01*
G01X362500Y26400D02*
Y32400D01*
G01X436619Y-162685D02*
Y-242685D01*
G01X487320Y98604D02*
Y103604D01*
G01X517758Y103534D02*
Y98534D01*
G01X604119Y-162685D02*
Y-242685D01*
G01X774119Y-162685D02*
Y-242685D01*
G01X971619Y-162685D02*
Y-242685D01*
G01X999619Y-146685D02*
G02I-12000J0D01*
G01X1003619D02*
X971619D01*
G01X994469D02*
G02I-6850J0D01*
G01X987619Y-162685D02*
Y-130685D01*
G54D11*
G01X0Y58268D02*
Y33071D01*
G01Y402756D02*
Y427953D01*
G01X5906Y315650D02*
Y340847D01*
G01Y685335D02*
Y710532D01*
G01X74016Y369685D02*
X43307D01*
G01X113386Y91339D02*
X82677D01*
G01X113386Y105118D02*
X82677D01*
G01X113386Y461024D02*
X82677D01*
G01X113386Y474803D02*
X82677D01*
G01X163386Y303937D02*
Y329134D01*
G01Y673622D02*
Y698819D01*
G01X273622Y196260D02*
Y165551D01*
G01X265748Y196260D02*
Y165551D01*
G01X285040Y361811D02*
X254331D01*
G01X285040Y369685D02*
X254331D01*
G01X273622Y565945D02*
Y535236D01*
G01X265748Y565945D02*
Y535236D01*
G01X293572Y69371D02*
G03Y61771I0J-3800D01*
G01D02*
X297372D01*
G01D02*
G03Y69371I0J3800D01*
G01D02*
X293572D01*
G01Y112087D02*
G03Y104487I0J-3800D01*
G01D02*
X297372D01*
G01D02*
G03Y112087I0J3800D01*
G01D02*
X293572D01*
G01X328690Y69371D02*
G03Y61771I0J-3800D01*
G01D02*
X332490D01*
G01D02*
G03Y69371I0J3800D01*
G01D02*
X328690D01*
G01Y112087D02*
G03Y104487I0J-3800D01*
G01D02*
X332490D01*
G01D02*
G03Y112087I0J3800D01*
G01D02*
X328690D01*
G01X375985Y32677D02*
Y57874D01*
G01Y402362D02*
Y427559D01*
G01X456693Y256693D02*
X425985D01*
G01X456693Y270473D02*
X425985D01*
G01X456693Y640158D02*
X425985D01*
G01X456693Y626378D02*
X425985D01*
G01X489910Y86811D02*
G02I-4950J0D01*
G01X496063Y361811D02*
X465355D01*
G01X501721Y86811D02*
G02I-4950J0D01*
G01X513533D02*
G02I-4950J0D01*
G01X525344D02*
G02I-4950J0D01*
G01X533465Y46162D02*
Y20965D01*
G01X539370Y328740D02*
Y303543D01*
G01X533465Y415847D02*
Y390650D01*
G01X539370Y673228D02*
Y698425D01*
G54D12*
G01X59235Y78212D02*
Y81712D01*
G01X301300Y43300D02*
X298450D01*
Y40600D01*
G01X288007Y74129D02*
Y75929D01*
G01X318650Y29650D02*
X322500D01*
Y33450D01*
G01X317400Y223600D02*
X314550D01*
Y220900D01*
G54D13*
G01X291050Y55350D02*
X283300D01*
G01X332681Y206404D02*
X324931D01*
G54D14*
G01X332500Y167300D02*
X324800D01*
G01X362131Y54854D02*
X354431D01*
G01X469177Y90811D02*
Y95811D01*
X474177D01*
G54D15*
G01X304500Y143000D02*
Y139600D01*
G01X335000Y30000D02*
Y26600D01*
G54D16*
G01X-116181Y-215185D02*
Y-232685D01*
G01X-121203Y-215185D02*
X-111159D01*
G01X-103048Y-232685D02*
Y-215185D01*
X-97808D01*
X-96061Y-216060D01*
X-94751Y-218102D01*
X-94314Y-220435D01*
X-94751Y-222768D01*
X-95843Y-224518D01*
X-97808Y-225394D01*
X-103048D01*
G01X-58878Y-216644D02*
X-60188Y-215768D01*
X-61716Y-215185D01*
X-63463D01*
X-65428Y-216060D01*
X-66956Y-217518D01*
X-68048Y-219269D01*
X-68921Y-222185D01*
X-69140Y-224810D01*
X-68703Y-227435D01*
X-68048Y-229185D01*
X-66738Y-230935D01*
X-65209Y-232102D01*
X-63681Y-232685D01*
X-62153D01*
X-60624Y-232102D01*
X-59314Y-231227D01*
X-58222Y-230061D01*
G01X-49893Y-232685D02*
Y-215185D01*
G01Y-223643D02*
X-48801Y-222185D01*
X-47709Y-221310D01*
X-45963Y-221019D01*
X-44653Y-221310D01*
X-43124Y-222477D01*
X-42469Y-224227D01*
Y-232685D01*
G01X-24751D02*
Y-221019D01*
G01Y-223060D02*
X-25624Y-221894D01*
X-26935Y-221310D01*
X-28463Y-221019D01*
X-29991Y-221602D01*
X-31301Y-222768D01*
X-32175Y-224518D01*
X-32611Y-226852D01*
X-32175Y-229185D01*
X-31301Y-230935D01*
X-29991Y-232102D01*
X-28463Y-232685D01*
X-26935Y-232393D01*
X-25624Y-231519D01*
X-24751Y-230352D01*
G01X-14893Y-232685D02*
Y-221019D01*
G01Y-223935D02*
X-14019Y-222477D01*
X-12709Y-221310D01*
X-10963Y-221019D01*
X-9435Y-221310D01*
X-8124Y-222477D01*
X-7469Y-224518D01*
Y-232685D01*
G01X2607D02*
Y-221019D01*
G01Y-223935D02*
X3481Y-222477D01*
X4791Y-221310D01*
X6537Y-221019D01*
X8065Y-221310D01*
X9376Y-222477D01*
X10031Y-224518D01*
Y-232685D01*
G01X20544Y-224810D02*
X27531D01*
X26876Y-222768D01*
X25784Y-221602D01*
X24256Y-221019D01*
X22727Y-221310D01*
X21417Y-222185D01*
X20544Y-224227D01*
X20107Y-225977D01*
Y-227727D01*
X20544Y-229477D01*
X21636Y-231227D01*
X22946Y-232393D01*
X24474Y-232685D01*
X26002Y-232102D01*
X27531Y-230352D01*
G01X41319Y-232685D02*
Y-215185D01*
G01X71734Y-232685D02*
Y-215185D01*
G01X80904D02*
Y-232685D01*
G01Y-223935D02*
X71734D01*
G01X89016Y-232685D02*
Y-215185D01*
X93382D01*
X95129Y-216060D01*
X96439Y-217227D01*
X97531Y-218976D01*
X98404Y-221019D01*
X98622Y-223935D01*
X98404Y-226852D01*
X97531Y-228894D01*
X96439Y-230644D01*
X95129Y-231810D01*
X93382Y-232685D01*
X89016D01*
G01X106516D02*
Y-215185D01*
X110882D01*
X112629Y-216060D01*
X113939Y-217227D01*
X115031Y-218976D01*
X115904Y-221019D01*
X116122Y-223935D01*
X115904Y-226852D01*
X115031Y-228894D01*
X113939Y-230644D01*
X112629Y-231810D01*
X110882Y-232685D01*
X106516D01*
G01X148065Y-223352D02*
X148939Y-222477D01*
X149594Y-221019D01*
X150031Y-218976D01*
X149594Y-217227D01*
X148721Y-216060D01*
X147192Y-215185D01*
X141297D01*
Y-232685D01*
X148502D01*
X150031Y-231519D01*
X150904Y-229768D01*
X151341Y-227727D01*
X150904Y-225685D01*
X149594Y-223935D01*
X148065Y-223352D01*
X141297D01*
G01X159452Y-232685D02*
Y-215185D01*
X164692D01*
X166439Y-216060D01*
X167749Y-218102D01*
X168186Y-220435D01*
X167749Y-222768D01*
X166657Y-224518D01*
X164692Y-225394D01*
X159452D01*
G01X-16858Y-187685D02*
Y-170185D01*
X-11181Y-184768D01*
X-5504Y-170185D01*
Y-187685D01*
G01X6319D02*
X5009Y-187393D01*
X3699Y-186227D01*
X2825Y-184185D01*
X2389Y-181852D01*
X2825Y-179518D01*
X3699Y-177477D01*
X5009Y-176310D01*
X6319Y-176019D01*
X7629Y-176310D01*
X8939Y-177477D01*
X9812Y-179518D01*
X10031Y-181852D01*
X9812Y-184185D01*
X8939Y-186227D01*
X7629Y-187393D01*
X6319Y-187685D01*
G01X27749Y-170185D02*
Y-187685D01*
G01Y-185061D02*
X26876Y-186519D01*
X25565Y-187393D01*
X24037Y-187685D01*
X22291Y-187102D01*
X20981Y-185644D01*
X20107Y-183894D01*
X19889Y-181852D01*
X20107Y-179810D01*
X20981Y-178060D01*
X22291Y-176602D01*
X24037Y-176019D01*
X25565Y-176310D01*
X26657Y-176894D01*
X27749Y-178060D01*
G01X38044Y-179810D02*
X45031D01*
X44376Y-177768D01*
X43284Y-176602D01*
X41756Y-176019D01*
X40227Y-176310D01*
X38917Y-177185D01*
X38044Y-179227D01*
X37607Y-180977D01*
Y-182727D01*
X38044Y-184477D01*
X39136Y-186227D01*
X40446Y-187393D01*
X41974Y-187685D01*
X43502Y-187102D01*
X45031Y-185352D01*
G01X58819Y-187685D02*
Y-170185D01*
G01X204702Y-187685D02*
Y-170185D01*
X209942D01*
X211689Y-171060D01*
X212999Y-173102D01*
X213436Y-175435D01*
X212999Y-177768D01*
X211907Y-179518D01*
X209942Y-180394D01*
X204702D01*
G01X231372Y-171644D02*
X230062Y-170768D01*
X228534Y-170185D01*
X226787D01*
X224822Y-171060D01*
X223294Y-172518D01*
X222202Y-174269D01*
X221329Y-177185D01*
X221110Y-179810D01*
X221547Y-182435D01*
X222202Y-184185D01*
X223512Y-185935D01*
X225041Y-187102D01*
X226569Y-187685D01*
X228097D01*
X229626Y-187102D01*
X230936Y-186227D01*
X232028Y-185061D01*
G01X245815Y-178352D02*
X246689Y-177477D01*
X247344Y-176019D01*
X247781Y-173976D01*
X247344Y-172227D01*
X246471Y-171060D01*
X244942Y-170185D01*
X239047D01*
Y-187685D01*
X246252D01*
X247781Y-186519D01*
X248654Y-184768D01*
X249091Y-182727D01*
X248654Y-180685D01*
X247344Y-178935D01*
X245815Y-178352D01*
X239047D01*
G01X255019Y-193518D02*
X268119D01*
G01X274047Y-187685D02*
Y-170185D01*
X284091Y-187685D01*
Y-170185D01*
G01X296569Y-187685D02*
X294822Y-187393D01*
X293294Y-186227D01*
X291984Y-184477D01*
X291110Y-182435D01*
X290674Y-180102D01*
Y-177768D01*
X291110Y-175435D01*
X291984Y-173393D01*
X293294Y-171644D01*
X294822Y-170477D01*
X296569Y-170185D01*
X298315Y-170477D01*
X299844Y-171644D01*
X301154Y-173393D01*
X302028Y-175435D01*
X302464Y-177768D01*
Y-180102D01*
X302028Y-182435D01*
X301154Y-184477D01*
X299844Y-186227D01*
X298315Y-187393D01*
X296569Y-187685D01*
G01X217819Y-232685D02*
Y-215185D01*
X215199Y-218685D01*
G01Y-232685D02*
X220439D01*
G01X234882D02*
X235319Y-228894D01*
X235974Y-225685D01*
X236847Y-222768D01*
X237939Y-219560D01*
X239686Y-215185D01*
X230952D01*
G01X248016Y-229185D02*
X249325Y-231227D01*
X251072Y-232393D01*
X253037Y-232685D01*
X254784Y-232393D01*
X256531Y-230935D01*
X257622Y-229185D01*
X257841Y-227435D01*
X257404Y-225394D01*
X255876Y-223935D01*
X254347Y-223352D01*
X252382D01*
G01X254347D02*
X255657Y-222477D01*
X256749Y-221019D01*
X257186Y-219269D01*
X256749Y-217518D01*
X255657Y-216060D01*
X253692Y-215185D01*
X251727Y-215477D01*
X249762Y-216644D01*
G01X270319Y-215185D02*
X268572Y-215768D01*
X267262Y-217227D01*
X266389Y-218976D01*
X265734Y-221310D01*
X265516Y-223935D01*
X265734Y-226560D01*
X266389Y-228894D01*
X267262Y-230644D01*
X268572Y-232102D01*
X270319Y-232685D01*
X272065Y-232102D01*
X273376Y-230644D01*
X274249Y-228894D01*
X274904Y-226560D01*
X275122Y-223935D01*
X274904Y-221310D01*
X274249Y-218976D01*
X273376Y-217227D01*
X272065Y-215768D01*
X270319Y-215185D01*
G01X287819Y-232685D02*
Y-215185D01*
X285199Y-218685D01*
G01Y-232685D02*
X290439D01*
G01X365784Y-230352D02*
X367531Y-231810D01*
X369496Y-232685D01*
X371242D01*
X372989Y-231810D01*
X374299Y-230352D01*
X374954Y-228310D01*
X374517Y-226269D01*
X373426Y-224518D01*
X371461Y-223352D01*
X368841Y-222768D01*
X367312Y-221602D01*
X366657Y-219560D01*
X367094Y-217518D01*
X368186Y-216060D01*
X369714Y-215185D01*
X371242D01*
X372771Y-215768D01*
X374081Y-217227D01*
G01X382410Y-232685D02*
X387869Y-215185D01*
X393328Y-232685D01*
G01X391362Y-226560D02*
X384375D01*
G01X347410Y-170185D02*
X352869Y-187685D01*
X358328Y-170185D01*
G01X374736Y-187685D02*
X366002D01*
Y-170185D01*
X374736D01*
G01X371242Y-178643D02*
X366002D01*
G01X383502Y-187685D02*
Y-170185D01*
X388961D01*
X390707Y-171060D01*
X391799Y-172227D01*
X392236Y-174560D01*
X391799Y-176894D01*
X390489Y-178352D01*
X388961Y-179227D01*
X383502D01*
G01X388961D02*
X392236Y-187685D01*
G01X405369Y-188268D02*
X404932Y-187977D01*
Y-187393D01*
X405369Y-187102D01*
X405806Y-187393D01*
Y-187977D01*
X405369Y-188268D01*
G01X553573Y-223352D02*
X552699Y-222477D01*
X552044Y-221019D01*
X551607Y-218976D01*
X552044Y-217227D01*
X552917Y-216060D01*
X554446Y-215185D01*
X560341D01*
Y-232685D01*
X553136D01*
X551607Y-231519D01*
X550734Y-229768D01*
X550297Y-227727D01*
X550734Y-225685D01*
X552044Y-223935D01*
X553573Y-223352D01*
X560341D01*
G01X542404Y-230352D02*
X540657Y-231810D01*
X538692Y-232685D01*
X536946D01*
X535199Y-231810D01*
X533889Y-230352D01*
X533234Y-228310D01*
X533671Y-226269D01*
X534762Y-224518D01*
X536727Y-223352D01*
X539347Y-222768D01*
X540876Y-221602D01*
X541531Y-219560D01*
X541094Y-217518D01*
X540002Y-216060D01*
X538474Y-215185D01*
X536946D01*
X535417Y-215768D01*
X534107Y-217227D01*
G01X522939Y-215185D02*
X517699D01*
G01X520319D02*
Y-232685D01*
G01X522939D02*
X517699D01*
G01X507186Y-215185D02*
Y-232685D01*
X498452D01*
G01X490122D02*
Y-215185D01*
G01X481826D02*
X490122Y-225977D01*
G01X480516Y-232685D02*
X486411Y-221019D01*
G01X480952Y-170185D02*
Y-187685D01*
X489686D01*
G01X506749D02*
Y-176019D01*
G01Y-178060D02*
X505876Y-176894D01*
X504565Y-176310D01*
X503037Y-176019D01*
X501509Y-176602D01*
X500199Y-177768D01*
X499325Y-179518D01*
X498889Y-181852D01*
X499325Y-184185D01*
X500199Y-185935D01*
X501509Y-187102D01*
X503037Y-187685D01*
X504565Y-187393D01*
X505876Y-186519D01*
X506749Y-185352D01*
G01X515734Y-192935D02*
X517044Y-193518D01*
X518791Y-192935D01*
X519882Y-191769D01*
X520756Y-190310D01*
X522065Y-185644D01*
X524904Y-176019D01*
G01X517917D02*
X522065Y-185644D01*
G01X534544Y-179810D02*
X541531D01*
X540876Y-177768D01*
X539784Y-176602D01*
X538256Y-176019D01*
X536727Y-176310D01*
X535417Y-177185D01*
X534544Y-179227D01*
X534107Y-180977D01*
Y-182727D01*
X534544Y-184477D01*
X535636Y-186227D01*
X536946Y-187393D01*
X538474Y-187685D01*
X540002Y-187102D01*
X541531Y-185352D01*
G01X552262Y-187685D02*
Y-176019D01*
G01Y-178352D02*
X553354Y-177185D01*
X554446Y-176310D01*
X555974Y-176019D01*
X557065Y-176310D01*
X558376Y-177185D01*
G01X623066Y-187685D02*
Y-170185D01*
X627432D01*
X629179Y-171060D01*
X630489Y-172227D01*
X631581Y-173976D01*
X632454Y-176019D01*
X632672Y-178935D01*
X632454Y-181852D01*
X631581Y-183894D01*
X630489Y-185644D01*
X629179Y-186810D01*
X627432Y-187685D01*
X623066D01*
G01X642094Y-179810D02*
X649081D01*
X648426Y-177768D01*
X647334Y-176602D01*
X645806Y-176019D01*
X644277Y-176310D01*
X642967Y-177185D01*
X642094Y-179227D01*
X641657Y-180977D01*
Y-182727D01*
X642094Y-184477D01*
X643186Y-186227D01*
X644496Y-187393D01*
X646024Y-187685D01*
X647552Y-187102D01*
X649081Y-185352D01*
G01X659594Y-185644D02*
X660686Y-186810D01*
X662214Y-187685D01*
X663524D01*
X664834Y-187102D01*
X665707Y-186227D01*
X666144Y-185061D01*
X665926Y-183310D01*
X665052Y-182435D01*
X661122Y-180685D01*
X660249Y-178643D01*
X660686Y-177185D01*
X661559Y-176310D01*
X662869Y-176019D01*
X664179Y-176310D01*
X665489Y-177185D01*
G01X680369Y-176019D02*
Y-187685D01*
G01Y-171352D02*
X679932Y-171060D01*
Y-170477D01*
X680369Y-170185D01*
X680806Y-170477D01*
Y-171060D01*
X680369Y-171352D01*
G01X694812Y-192060D02*
X696341Y-193227D01*
X698087Y-193518D01*
X699615Y-193227D01*
X700926Y-191769D01*
X701799Y-189727D01*
Y-176019D01*
G01Y-178352D02*
X700926Y-177185D01*
X699615Y-176310D01*
X698087Y-176019D01*
X696341Y-176602D01*
X695249Y-177768D01*
X694375Y-179810D01*
X693939Y-181852D01*
X694157Y-183602D01*
X695031Y-185644D01*
X696341Y-187102D01*
X698087Y-187685D01*
X699397Y-187393D01*
X700926Y-186227D01*
X701799Y-185061D01*
G01X711657Y-187685D02*
Y-176019D01*
G01Y-178935D02*
X712531Y-177477D01*
X713841Y-176310D01*
X715587Y-176019D01*
X717115Y-176310D01*
X718426Y-177477D01*
X719081Y-179518D01*
Y-187685D01*
G01X729594Y-179810D02*
X736581D01*
X735926Y-177768D01*
X734834Y-176602D01*
X733306Y-176019D01*
X731777Y-176310D01*
X730467Y-177185D01*
X729594Y-179227D01*
X729157Y-180977D01*
Y-182727D01*
X729594Y-184477D01*
X730686Y-186227D01*
X731996Y-187393D01*
X733524Y-187685D01*
X735052Y-187102D01*
X736581Y-185352D01*
G01X747312Y-187685D02*
Y-176019D01*
G01Y-178352D02*
X748404Y-177185D01*
X749496Y-176310D01*
X751024Y-176019D01*
X752115Y-176310D01*
X753426Y-177185D01*
G01X664179Y-223935D02*
X668546D01*
Y-229185D01*
X667236Y-230935D01*
X665707Y-232102D01*
X663524Y-232685D01*
X661341Y-232102D01*
X659812Y-230935D01*
X658502Y-229185D01*
X657629Y-227143D01*
X657192Y-224810D01*
Y-222768D01*
X657629Y-221019D01*
X658502Y-218976D01*
X659812Y-217227D01*
X661122Y-216060D01*
X662869Y-215185D01*
X664397D01*
X666144Y-215768D01*
X667454Y-216935D01*
G01X684736Y-232685D02*
X676002D01*
Y-215185D01*
X684736D01*
G01X681242Y-223643D02*
X676002D01*
G01X693502Y-215185D02*
Y-232685D01*
X702236D01*
G01X715369D02*
X713622Y-232393D01*
X712094Y-231227D01*
X710784Y-229477D01*
X709910Y-227435D01*
X709474Y-225102D01*
Y-222768D01*
X709910Y-220435D01*
X710784Y-218393D01*
X712094Y-216644D01*
X713622Y-215477D01*
X715369Y-215185D01*
X717115Y-215477D01*
X718644Y-216644D01*
X719954Y-218393D01*
X720828Y-220435D01*
X721264Y-222768D01*
Y-225102D01*
X720828Y-227435D01*
X719954Y-229477D01*
X718644Y-231227D01*
X717115Y-232393D01*
X715369Y-232685D01*
G01X794069Y-215185D02*
X792322Y-215768D01*
X791012Y-217227D01*
X790139Y-218976D01*
X789484Y-221310D01*
X789266Y-223935D01*
X789484Y-226560D01*
X790139Y-228894D01*
X791012Y-230644D01*
X792322Y-232102D01*
X794069Y-232685D01*
X795815Y-232102D01*
X797126Y-230644D01*
X797999Y-228894D01*
X798654Y-226560D01*
X798872Y-223935D01*
X798654Y-221310D01*
X797999Y-218976D01*
X797126Y-217227D01*
X795815Y-215768D01*
X794069Y-215185D01*
G01X807421Y-225394D02*
X808949Y-223352D01*
X810259Y-222185D01*
X812006Y-221602D01*
X813534Y-222185D01*
X814626Y-223352D01*
X815499Y-225102D01*
X815717Y-227143D01*
X815499Y-228894D01*
X814626Y-230644D01*
X813315Y-232102D01*
X811787Y-232685D01*
X810041Y-232102D01*
X808512Y-230352D01*
X807639Y-227727D01*
X807421Y-224810D01*
X807857Y-221019D01*
X808512Y-218976D01*
X809604Y-216935D01*
X811132Y-215477D01*
X812661Y-215185D01*
X814189Y-215768D01*
X815281Y-217227D01*
G01X825139Y-233268D02*
X832999Y-215185D01*
G01X842421Y-218102D02*
X843731Y-216352D01*
X845259Y-215477D01*
X847006Y-215185D01*
X849189Y-215768D01*
X850717Y-217227D01*
X851154Y-218976D01*
X850936Y-220727D01*
X850062Y-222185D01*
X845696Y-225102D01*
X843731Y-227143D01*
X842421Y-230061D01*
X841984Y-232685D01*
X851154D01*
G01X859921Y-218102D02*
X861231Y-216352D01*
X862759Y-215477D01*
X864506Y-215185D01*
X866689Y-215768D01*
X868217Y-217227D01*
X868654Y-218976D01*
X868436Y-220727D01*
X867562Y-222185D01*
X863196Y-225102D01*
X861231Y-227143D01*
X859921Y-230061D01*
X859484Y-232685D01*
X868654D01*
G01X877639Y-233268D02*
X885499Y-215185D01*
G01X894921Y-218102D02*
X896231Y-216352D01*
X897759Y-215477D01*
X899506Y-215185D01*
X901689Y-215768D01*
X903217Y-217227D01*
X903654Y-218976D01*
X903436Y-220727D01*
X902562Y-222185D01*
X898196Y-225102D01*
X896231Y-227143D01*
X894921Y-230061D01*
X894484Y-232685D01*
X903654D01*
G01X916569Y-215185D02*
X914822Y-215768D01*
X913512Y-217227D01*
X912639Y-218976D01*
X911984Y-221310D01*
X911766Y-223935D01*
X911984Y-226560D01*
X912639Y-228894D01*
X913512Y-230644D01*
X914822Y-232102D01*
X916569Y-232685D01*
X918315Y-232102D01*
X919626Y-230644D01*
X920499Y-228894D01*
X921154Y-226560D01*
X921372Y-223935D01*
X921154Y-221310D01*
X920499Y-218976D01*
X919626Y-217227D01*
X918315Y-215768D01*
X916569Y-215185D01*
G01X934069Y-232685D02*
Y-215185D01*
X931449Y-218685D01*
G01Y-232685D02*
X936689D01*
G01X951132D02*
X951569Y-228894D01*
X952224Y-225685D01*
X953097Y-222768D01*
X954189Y-219560D01*
X955936Y-215185D01*
X947202D01*
G01X841766Y-187685D02*
Y-170185D01*
X846132D01*
X847879Y-171060D01*
X849189Y-172227D01*
X850281Y-173976D01*
X851154Y-176019D01*
X851372Y-178935D01*
X851154Y-181852D01*
X850281Y-183894D01*
X849189Y-185644D01*
X847879Y-186810D01*
X846132Y-187685D01*
X841766D01*
G01X867999D02*
Y-176019D01*
G01Y-178060D02*
X867126Y-176894D01*
X865815Y-176310D01*
X864287Y-176019D01*
X862759Y-176602D01*
X861449Y-177768D01*
X860575Y-179518D01*
X860139Y-181852D01*
X860575Y-184185D01*
X861449Y-185935D01*
X862759Y-187102D01*
X864287Y-187685D01*
X865815Y-187393D01*
X867126Y-186519D01*
X867999Y-185352D01*
G01X881569Y-170185D02*
Y-187685D01*
G01X878512Y-176019D02*
X884626D01*
G01X895794Y-179810D02*
X902781D01*
X902126Y-177768D01*
X901034Y-176602D01*
X899506Y-176019D01*
X897977Y-176310D01*
X896667Y-177185D01*
X895794Y-179227D01*
X895357Y-180977D01*
Y-182727D01*
X895794Y-184477D01*
X896886Y-186227D01*
X898196Y-187393D01*
X899724Y-187685D01*
X901252Y-187102D01*
X902781Y-185352D01*
G01X36585Y37562D02*
X40085D01*
Y17062D01*
X58885D01*
Y87662D01*
X40085D01*
Y67162D01*
X36585D01*
Y37562D01*
G01X56683Y14542D02*
X56933Y14667D01*
X57225Y14750D01*
X57558D01*
X57933Y14625D01*
X58225Y14417D01*
X58433Y14167D01*
X58600Y13750D01*
X58642Y13375D01*
X58558Y13000D01*
X58433Y12750D01*
X58183Y12500D01*
X57892Y12333D01*
X57600Y12250D01*
X57308D01*
X57017Y12333D01*
X56767Y12458D01*
X56558Y12625D01*
G01X55458Y12250D02*
Y14750D01*
X53542Y12250D01*
Y14750D01*
G01X51400Y12250D02*
Y14750D01*
X51900Y14250D01*
G01Y12250D02*
X50900D01*
G01X269271Y14819D02*
X269604Y14861D01*
X269896Y15027D01*
X270146Y15277D01*
X270313Y15569D01*
X270396Y15902D01*
Y16236D01*
X270313Y16569D01*
X270146Y16861D01*
X269896Y17111D01*
X269604Y17277D01*
X269271Y17319D01*
X268938Y17277D01*
X268646Y17111D01*
X268396Y16861D01*
X268229Y16569D01*
X268146Y16236D01*
Y15902D01*
X268229Y15569D01*
X268396Y15277D01*
X268646Y15027D01*
X268938Y14861D01*
X269271Y14819D01*
G01X268938Y15486D02*
X268438Y14819D01*
G01X266879Y15111D02*
X266588Y14902D01*
X266254Y14819D01*
X265921Y14902D01*
X265629Y15152D01*
X265421Y15527D01*
X265338Y15902D01*
Y16361D01*
X265421Y16736D01*
X265629Y17069D01*
X265879Y17236D01*
X266171Y17319D01*
X266504Y17236D01*
X266754Y17069D01*
X266921Y16819D01*
X267004Y16486D01*
X266921Y16194D01*
X266713Y15902D01*
X266463Y15736D01*
X266171Y15694D01*
X265838Y15777D01*
X265588Y15986D01*
X265338Y16361D01*
G01X265721Y19069D02*
Y33069D01*
G01X278721Y19069D02*
X265721D01*
G01Y33069D02*
X278721D01*
G01X271100Y58250D02*
X271433Y58292D01*
X271725Y58458D01*
X271975Y58708D01*
X272142Y59000D01*
X272225Y59333D01*
Y59667D01*
X272142Y60000D01*
X271975Y60292D01*
X271725Y60542D01*
X271433Y60708D01*
X271100Y60750D01*
X270767Y60708D01*
X270475Y60542D01*
X270225Y60292D01*
X270058Y60000D01*
X269975Y59667D01*
Y59333D01*
X270058Y59000D01*
X270225Y58708D01*
X270475Y58458D01*
X270767Y58292D01*
X271100Y58250D01*
G01X270767Y58917D02*
X270267Y58250D01*
G01X268000D02*
Y60750D01*
X268500Y60250D01*
G01Y58250D02*
X267500D01*
G01X264900Y60750D02*
X265233Y60667D01*
X265483Y60458D01*
X265650Y60208D01*
X265775Y59875D01*
X265817Y59500D01*
X265775Y59125D01*
X265650Y58792D01*
X265483Y58542D01*
X265233Y58333D01*
X264900Y58250D01*
X264567Y58333D01*
X264317Y58542D01*
X264150Y58792D01*
X264025Y59125D01*
X263983Y59500D01*
X264025Y59875D01*
X264150Y60208D01*
X264317Y60458D01*
X264567Y60667D01*
X264900Y60750D01*
G01X275500Y55700D02*
X277300Y53600D01*
X279500Y55700D01*
G01X283100Y55800D02*
Y36600D01*
X271900D01*
Y55800D01*
X283100D01*
Y55400D01*
G01X282554Y57627D02*
Y60127D01*
X281554D01*
X281221Y60002D01*
X280971Y59710D01*
X280888Y59377D01*
X280971Y59044D01*
X281179Y58794D01*
X281554Y58669D01*
X282554D01*
G01X279454Y57627D02*
Y60127D01*
X278413D01*
X278079Y60002D01*
X277871Y59835D01*
X277788Y59502D01*
X277871Y59169D01*
X278121Y58960D01*
X278413Y58835D01*
X279454D01*
G01X278413D02*
X277788Y57627D01*
G01X275521D02*
Y60127D01*
X276021Y59627D01*
G01Y57627D02*
X275021D01*
G01X284583Y11245D02*
X287083D01*
Y12286D01*
X286958Y12620D01*
X286791Y12828D01*
X286458Y12911D01*
X286125Y12828D01*
X285916Y12578D01*
X285791Y12286D01*
Y11245D01*
G01Y12286D02*
X284583Y12911D01*
G01Y15178D02*
X287083D01*
X286583Y14678D01*
G01X284583D02*
Y15678D01*
G01X285625Y17486D02*
X285916Y17778D01*
X286083Y18028D01*
X286166Y18361D01*
X286083Y18653D01*
X285916Y18861D01*
X285666Y19028D01*
X285375Y19070D01*
X285125Y19028D01*
X284875Y18861D01*
X284666Y18611D01*
X284583Y18320D01*
X284666Y17986D01*
X284916Y17695D01*
X285291Y17528D01*
X285708Y17486D01*
X286250Y17570D01*
X286541Y17695D01*
X286833Y17903D01*
X287041Y18195D01*
X287083Y18486D01*
X287000Y18778D01*
X286791Y18986D01*
G01X284583Y21295D02*
X285125Y21378D01*
X285583Y21503D01*
X286000Y21670D01*
X286458Y21878D01*
X287083Y22211D01*
Y20545D01*
G01X282875Y12995D02*
X283000Y12745D01*
X283083Y12453D01*
Y12120D01*
X282958Y11745D01*
X282750Y11453D01*
X282500Y11245D01*
X282083Y11078D01*
X281708Y11036D01*
X281333Y11120D01*
X281083Y11245D01*
X280833Y11495D01*
X280666Y11786D01*
X280583Y12078D01*
Y12370D01*
X280666Y12661D01*
X280791Y12911D01*
X280958Y13120D01*
G01Y14261D02*
X280750Y14511D01*
X280625Y14803D01*
X280583Y15178D01*
X280666Y15553D01*
X280833Y15845D01*
X281125Y16053D01*
X281458Y16095D01*
X281791Y16011D01*
X282000Y15803D01*
X282166Y15511D01*
X282208Y15220D01*
X282166Y14928D01*
X282000Y14553D01*
X283083Y14678D01*
Y15803D01*
G01X280583Y18278D02*
X283083D01*
X282583Y17778D01*
G01X280583D02*
Y18778D01*
G01Y21295D02*
X281125Y21378D01*
X281583Y21503D01*
X282000Y21670D01*
X282458Y21878D01*
X283083Y22211D01*
Y20545D01*
G01X278721Y33069D02*
Y19069D01*
G01X283083Y31928D02*
X287083D01*
Y24528D01*
G01X296287Y31341D02*
X294495D01*
X294120Y31508D01*
X293870Y31841D01*
X293787Y32258D01*
X293870Y32675D01*
X294120Y33008D01*
X294495Y33175D01*
X296287D01*
G01X293787Y35358D02*
X296287D01*
X295787Y34858D01*
G01X293787D02*
Y35858D01*
G01Y38375D02*
X294329Y38458D01*
X294787Y38583D01*
X295204Y38750D01*
X295662Y38958D01*
X296287Y39291D01*
Y37625D01*
G01X302593Y47060D02*
X302843Y47185D01*
X303135Y47268D01*
X303468D01*
X303843Y47143D01*
X304135Y46935D01*
X304343Y46685D01*
X304510Y46268D01*
X304552Y45893D01*
X304468Y45518D01*
X304343Y45268D01*
X304093Y45018D01*
X303802Y44851D01*
X303510Y44768D01*
X303218D01*
X302927Y44851D01*
X302677Y44976D01*
X302468Y45143D01*
G01X301327Y45268D02*
X301077Y44976D01*
X300743Y44810D01*
X300368Y44768D01*
X300035Y44810D01*
X299702Y45018D01*
X299493Y45268D01*
X299452Y45518D01*
X299535Y45810D01*
X299827Y46018D01*
X300118Y46101D01*
X300493D01*
G01X300118D02*
X299868Y46226D01*
X299660Y46435D01*
X299577Y46685D01*
X299660Y46935D01*
X299868Y47143D01*
X300243Y47268D01*
X300618Y47226D01*
X300993Y47060D01*
G01X298227Y45143D02*
X297977Y44935D01*
X297685Y44810D01*
X297310Y44768D01*
X296935Y44851D01*
X296643Y45018D01*
X296435Y45310D01*
X296393Y45643D01*
X296477Y45976D01*
X296685Y46185D01*
X296977Y46351D01*
X297268Y46393D01*
X297560Y46351D01*
X297935Y46185D01*
X297810Y47268D01*
X296685D01*
G01X292877Y48195D02*
X295377D01*
Y49195D01*
X295252Y49528D01*
X294960Y49778D01*
X294627Y49861D01*
X294294Y49778D01*
X294044Y49570D01*
X293919Y49195D01*
Y48195D01*
G01X292877Y52128D02*
X292919Y51795D01*
X293085Y51503D01*
X293335Y51253D01*
X293627Y51086D01*
X293960Y51003D01*
X294294D01*
X294627Y51086D01*
X294919Y51253D01*
X295169Y51503D01*
X295335Y51795D01*
X295377Y52128D01*
X295335Y52461D01*
X295169Y52753D01*
X294919Y53003D01*
X294627Y53170D01*
X294294Y53253D01*
X293960D01*
X293627Y53170D01*
X293335Y53003D01*
X293085Y52753D01*
X292919Y52461D01*
X292877Y52128D01*
G01X293544Y52461D02*
X292877Y52961D01*
G01Y55228D02*
X295377D01*
X294877Y54728D01*
G01X292877D02*
Y55728D01*
G01X297144Y59682D02*
Y49782D01*
G01D02*
X310844D01*
G01Y59682D02*
X297144D01*
G01X288357Y61979D02*
X345157D01*
Y73629D01*
X346157D01*
Y100229D01*
X345157D01*
Y111879D01*
X288357D01*
Y61979D01*
G01X295633Y138792D02*
X295883Y138917D01*
X296175Y139000D01*
X296508D01*
X296883Y138875D01*
X297175Y138667D01*
X297383Y138417D01*
X297550Y138000D01*
X297592Y137625D01*
X297508Y137250D01*
X297383Y137000D01*
X297133Y136750D01*
X296842Y136583D01*
X296550Y136500D01*
X296258D01*
X295967Y136583D01*
X295717Y136708D01*
X295508Y136875D01*
G01X293450Y136500D02*
Y139000D01*
X293950Y138500D01*
G01Y136500D02*
X292950D01*
G01X290350D02*
Y139000D01*
X290850Y138500D01*
G01Y136500D02*
X289850D01*
G01X298600Y146000D02*
X304100D01*
G01X286500D02*
X292000D01*
G01X286500Y154000D02*
Y146000D01*
G01X295633Y142792D02*
X295883Y142917D01*
X296175Y143000D01*
X296508D01*
X296883Y142875D01*
X297175Y142667D01*
X297383Y142417D01*
X297550Y142000D01*
X297592Y141625D01*
X297508Y141250D01*
X297383Y141000D01*
X297133Y140750D01*
X296842Y140583D01*
X296550Y140500D01*
X296258D01*
X295967Y140583D01*
X295717Y140708D01*
X295508Y140875D01*
G01X293533Y140500D02*
X293450Y141042D01*
X293325Y141500D01*
X293158Y141917D01*
X292950Y142375D01*
X292617Y143000D01*
X294283D01*
G01X304100Y154000D02*
X298600D01*
G01X292000D02*
X286500D01*
G01X304100Y162700D02*
X298600D01*
G01Y154700D02*
X304100D01*
G01X286500D02*
X292000D01*
G01X286500Y162700D02*
Y154700D01*
G01X292000Y162700D02*
X286500D01*
G01X297183Y170292D02*
X297433Y170417D01*
X297725Y170500D01*
X298058D01*
X298433Y170375D01*
X298725Y170167D01*
X298933Y169917D01*
X299100Y169500D01*
X299142Y169125D01*
X299058Y168750D01*
X298933Y168500D01*
X298683Y168250D01*
X298392Y168083D01*
X298100Y168000D01*
X297808D01*
X297517Y168083D01*
X297267Y168208D01*
X297058Y168375D01*
G01X295000Y168000D02*
Y170500D01*
X295500Y170000D01*
G01Y168000D02*
X294500D01*
G01X292692Y170083D02*
X292442Y170333D01*
X292150Y170458D01*
X291817Y170500D01*
X291400Y170417D01*
X291108Y170208D01*
X291025Y169958D01*
X291067Y169708D01*
X291233Y169500D01*
X292067Y169083D01*
X292442Y168792D01*
X292692Y168375D01*
X292775Y168000D01*
X291025D01*
G01X308900Y29500D02*
Y42900D01*
G01X298900Y29500D02*
X308900D01*
G01X298900Y42900D02*
Y29500D01*
G01X322417Y24950D02*
Y23158D01*
X322250Y22783D01*
X321917Y22533D01*
X321500Y22450D01*
X321083Y22533D01*
X320750Y22783D01*
X320583Y23158D01*
Y24950D01*
G01X318400Y22450D02*
Y24950D01*
X318900Y24450D01*
G01Y22450D02*
X317900D01*
G01X315300D02*
X315008Y22492D01*
X314675Y22617D01*
X314467Y22825D01*
X314383Y23117D01*
X314467Y23408D01*
X314717Y23658D01*
X315092Y23783D01*
X315508D01*
X315758Y23867D01*
X315967Y24075D01*
X316050Y24367D01*
X315925Y24658D01*
X315633Y24867D01*
X315300Y24950D01*
X314967Y24867D01*
X314675Y24658D01*
X314550Y24367D01*
X314633Y24075D01*
X314842Y23867D01*
X315092Y23783D01*
X315508D01*
X315883Y23658D01*
X316133Y23408D01*
X316217Y23117D01*
X316133Y22825D01*
X315925Y22617D01*
X315592Y22492D01*
X315300Y22450D01*
G01X322100Y30000D02*
X310700D01*
G01D02*
Y43400D01*
G01X308900Y42900D02*
X298900D01*
G01X310700Y43400D02*
X322100D01*
G01X312624Y53203D02*
X328724D01*
G01X312624Y60203D02*
Y53203D01*
G01X325876Y46020D02*
Y48520D01*
X324876D01*
X324543Y48395D01*
X324293Y48103D01*
X324210Y47770D01*
X324293Y47437D01*
X324501Y47187D01*
X324876Y47062D01*
X325876D01*
G01X321026Y48312D02*
X321276Y48437D01*
X321568Y48520D01*
X321901D01*
X322276Y48395D01*
X322568Y48187D01*
X322776Y47937D01*
X322943Y47520D01*
X322985Y47145D01*
X322901Y46770D01*
X322776Y46520D01*
X322526Y46270D01*
X322235Y46103D01*
X321943Y46020D01*
X321651D01*
X321360Y46103D01*
X321110Y46228D01*
X320901Y46395D01*
G01X318843Y46020D02*
Y48520D01*
X319343Y48020D01*
G01Y46020D02*
X318343D01*
G01X310844Y49782D02*
Y59682D01*
G01X328724Y60203D02*
X312624D01*
G01X315967Y127750D02*
Y125958D01*
X315800Y125583D01*
X315467Y125333D01*
X315050Y125250D01*
X314633Y125333D01*
X314300Y125583D01*
X314133Y125958D01*
Y127750D01*
G01X311950Y125250D02*
X311658Y125292D01*
X311325Y125417D01*
X311117Y125625D01*
X311033Y125917D01*
X311117Y126208D01*
X311367Y126458D01*
X311742Y126583D01*
X312158D01*
X312408Y126667D01*
X312617Y126875D01*
X312700Y127167D01*
X312575Y127458D01*
X312283Y127667D01*
X311950Y127750D01*
X311617Y127667D01*
X311325Y127458D01*
X311200Y127167D01*
X311283Y126875D01*
X311492Y126667D01*
X311742Y126583D01*
X312158D01*
X312533Y126458D01*
X312783Y126208D01*
X312867Y125917D01*
X312783Y125625D01*
X312575Y125417D01*
X312242Y125292D01*
X311950Y125250D01*
G01X322333Y113750D02*
Y116250D01*
X321250Y114167D01*
X320167Y116250D01*
Y113750D01*
G01X318650Y116250D02*
X317650D01*
G01X318150D02*
Y113750D01*
G01X318650D02*
X317650D01*
G01X315925Y114083D02*
X315592Y113875D01*
X315217Y113750D01*
X314883D01*
X314550Y113875D01*
X314300Y114083D01*
X314175Y114375D01*
X314258Y114667D01*
X314467Y114917D01*
X314842Y115083D01*
X315342Y115167D01*
X315633Y115333D01*
X315758Y115625D01*
X315675Y115917D01*
X315467Y116125D01*
X315175Y116250D01*
X314883D01*
X314592Y116167D01*
X314342Y115958D01*
G01X312992Y113750D02*
X311950Y116250D01*
X310908Y113750D01*
G01X311283Y114625D02*
X312617D01*
G01X309725Y114083D02*
X309392Y113875D01*
X309017Y113750D01*
X308683D01*
X308350Y113875D01*
X308100Y114083D01*
X307975Y114375D01*
X308058Y114667D01*
X308267Y114917D01*
X308642Y115083D01*
X309142Y115167D01*
X309433Y115333D01*
X309558Y115625D01*
X309475Y115917D01*
X309267Y116125D01*
X308975Y116250D01*
X308683D01*
X308392Y116167D01*
X308142Y115958D01*
G01X305750Y113750D02*
Y116250D01*
X306250Y115750D01*
G01Y113750D02*
X305250D01*
G01X326467Y133750D02*
Y136250D01*
X325633D01*
X325300Y136125D01*
X325050Y135958D01*
X324842Y135708D01*
X324675Y135417D01*
X324633Y135000D01*
X324675Y134583D01*
X324842Y134292D01*
X325050Y134042D01*
X325300Y133875D01*
X325633Y133750D01*
X326467D01*
G01X322450D02*
Y136250D01*
X322950Y135750D01*
G01Y133750D02*
X321950D01*
G01X332400Y145000D02*
X316300D01*
G01Y138000D02*
X332400D01*
G01X316300Y145000D02*
Y138000D01*
G01X303800Y143700D02*
X315200D01*
G01X303800Y130300D02*
Y143700D01*
G01X315200Y130300D02*
X303800D01*
G01X315200Y143700D02*
Y130300D01*
G01X324600Y167800D02*
Y148600D01*
X313400D01*
Y167800D01*
X324600D01*
G01X304100Y146000D02*
Y154000D01*
G01X312729Y169694D02*
Y183694D01*
G01X325729Y169694D02*
X312729D01*
G01X309467Y172250D02*
Y170458D01*
X309300Y170083D01*
X308967Y169833D01*
X308550Y169750D01*
X308133Y169833D01*
X307800Y170083D01*
X307633Y170458D01*
Y172250D01*
G01X306158Y170042D02*
X305867Y169833D01*
X305533Y169750D01*
X305200Y169833D01*
X304908Y170083D01*
X304700Y170458D01*
X304617Y170833D01*
Y171292D01*
X304700Y171667D01*
X304908Y172000D01*
X305158Y172167D01*
X305450Y172250D01*
X305783Y172167D01*
X306033Y172000D01*
X306200Y171750D01*
X306283Y171417D01*
X306200Y171125D01*
X305992Y170833D01*
X305742Y170667D01*
X305450Y170625D01*
X305117Y170708D01*
X304867Y170917D01*
X304617Y171292D01*
G01X317000Y167800D02*
X319000Y165800D01*
X321000Y167800D01*
G01X304100Y154700D02*
Y162700D01*
G01X308550Y176250D02*
X308883Y176292D01*
X309175Y176458D01*
X309425Y176708D01*
X309592Y177000D01*
X309675Y177333D01*
Y177667D01*
X309592Y178000D01*
X309425Y178292D01*
X309175Y178542D01*
X308883Y178708D01*
X308550Y178750D01*
X308217Y178708D01*
X307925Y178542D01*
X307675Y178292D01*
X307508Y178000D01*
X307425Y177667D01*
Y177333D01*
X307508Y177000D01*
X307675Y176708D01*
X307925Y176458D01*
X308217Y176292D01*
X308550Y176250D01*
G01X308217Y176917D02*
X307717Y176250D01*
G01X305450D02*
X305158Y176292D01*
X304825Y176417D01*
X304617Y176625D01*
X304533Y176917D01*
X304617Y177208D01*
X304867Y177458D01*
X305242Y177583D01*
X305658D01*
X305908Y177667D01*
X306117Y177875D01*
X306200Y178167D01*
X306075Y178458D01*
X305783Y178667D01*
X305450Y178750D01*
X305117Y178667D01*
X304825Y178458D01*
X304700Y178167D01*
X304783Y177875D01*
X304992Y177667D01*
X305242Y177583D01*
X305658D01*
X306033Y177458D01*
X306283Y177208D01*
X306367Y176917D01*
X306283Y176625D01*
X306075Y176417D01*
X305742Y176292D01*
X305450Y176250D01*
G01X312729Y183694D02*
X325729D01*
G01X324731Y206854D02*
Y187654D01*
X313531D01*
Y206854D01*
X324731D01*
Y206454D01*
G01X317131Y206754D02*
X318931Y204654D01*
X321131Y206754D01*
G01X315000Y209800D02*
X325000D01*
G01X315000Y223200D02*
Y209800D01*
G01X324417Y228350D02*
Y226558D01*
X324250Y226183D01*
X323917Y225933D01*
X323500Y225850D01*
X323083Y225933D01*
X322750Y226183D01*
X322583Y226558D01*
Y228350D01*
G01X320400Y225850D02*
Y228350D01*
X320900Y227850D01*
G01Y225850D02*
X319900D01*
G01X318092Y226892D02*
X317800Y227183D01*
X317550Y227350D01*
X317217Y227433D01*
X316925Y227350D01*
X316717Y227183D01*
X316550Y226933D01*
X316508Y226642D01*
X316550Y226392D01*
X316717Y226142D01*
X316967Y225933D01*
X317258Y225850D01*
X317592Y225933D01*
X317883Y226183D01*
X318050Y226558D01*
X318092Y226975D01*
X318008Y227517D01*
X317883Y227808D01*
X317675Y228100D01*
X317383Y228308D01*
X317092Y228350D01*
X316800Y228267D01*
X316592Y228058D01*
G01X325000Y223200D02*
X315000D01*
G01X338017Y15750D02*
Y13958D01*
X337850Y13583D01*
X337517Y13333D01*
X337100Y13250D01*
X336683Y13333D01*
X336350Y13583D01*
X336183Y13958D01*
Y15750D01*
G01X334000Y13250D02*
Y15750D01*
X334500Y15250D01*
G01Y13250D02*
X333500D01*
G01X331817Y13750D02*
X331567Y13458D01*
X331233Y13292D01*
X330858Y13250D01*
X330525Y13292D01*
X330192Y13500D01*
X329983Y13750D01*
X329942Y14000D01*
X330025Y14292D01*
X330317Y14500D01*
X330608Y14583D01*
X330983D01*
G01X330608D02*
X330358Y14708D01*
X330150Y14917D01*
X330067Y15167D01*
X330150Y15417D01*
X330358Y15625D01*
X330733Y15750D01*
X331108Y15708D01*
X331483Y15542D01*
G01X322100Y43400D02*
Y30000D01*
G01X334300Y30700D02*
X345700D01*
G01X334300Y17300D02*
Y30700D01*
G01X345700Y17300D02*
X334300D01*
G01X354231Y55354D02*
Y36154D01*
X343031D01*
Y55354D01*
X354231D01*
G01X337933Y55750D02*
Y58250D01*
X336933D01*
X336600Y58125D01*
X336350Y57833D01*
X336267Y57500D01*
X336350Y57167D01*
X336558Y56917D01*
X336933Y56792D01*
X337933D01*
G01X334917Y55750D02*
Y58250D01*
X334083D01*
X333750Y58125D01*
X333500Y57958D01*
X333292Y57708D01*
X333125Y57417D01*
X333083Y57000D01*
X333125Y56583D01*
X333292Y56292D01*
X333500Y56042D01*
X333750Y55875D01*
X334083Y55750D01*
X334917D01*
G01X330900D02*
Y58250D01*
X331400Y57750D01*
G01Y55750D02*
X330400D01*
G01X328724Y53203D02*
Y60203D01*
G01X332400Y138000D02*
Y145000D01*
G01X325729Y183694D02*
Y169694D01*
G01X343690Y171943D02*
X346190D01*
Y172984D01*
X346065Y173318D01*
X345898Y173526D01*
X345565Y173609D01*
X345232Y173526D01*
X345023Y173276D01*
X344898Y172984D01*
Y171943D01*
G01Y172984D02*
X343690Y173609D01*
G01Y175876D02*
X346190D01*
X345690Y175376D01*
G01X343690D02*
Y176376D01*
G01X344732Y178184D02*
X345023Y178476D01*
X345190Y178726D01*
X345273Y179059D01*
X345190Y179351D01*
X345023Y179559D01*
X344773Y179726D01*
X344482Y179768D01*
X344232Y179726D01*
X343982Y179559D01*
X343773Y179309D01*
X343690Y179018D01*
X343773Y178684D01*
X344023Y178393D01*
X344398Y178226D01*
X344815Y178184D01*
X345357Y178268D01*
X345648Y178393D01*
X345940Y178601D01*
X346148Y178893D01*
X346190Y179184D01*
X346107Y179476D01*
X345898Y179684D01*
G01X343690Y182576D02*
X346190D01*
X344398Y181034D01*
Y183118D01*
G01X341982Y173693D02*
X342107Y173443D01*
X342190Y173151D01*
Y172818D01*
X342065Y172443D01*
X341857Y172151D01*
X341607Y171943D01*
X341190Y171776D01*
X340815Y171734D01*
X340440Y171818D01*
X340190Y171943D01*
X339940Y172193D01*
X339773Y172484D01*
X339690Y172776D01*
Y173068D01*
X339773Y173359D01*
X339898Y173609D01*
X340065Y173818D01*
G01Y174959D02*
X339857Y175209D01*
X339732Y175501D01*
X339690Y175876D01*
X339773Y176251D01*
X339940Y176543D01*
X340232Y176751D01*
X340565Y176793D01*
X340898Y176709D01*
X341107Y176501D01*
X341273Y176209D01*
X341315Y175918D01*
X341273Y175626D01*
X341107Y175251D01*
X342190Y175376D01*
Y176501D01*
G01X339690Y178976D02*
X342190D01*
X341690Y178476D01*
G01X339690D02*
Y179476D01*
G01X340732Y181284D02*
X341023Y181576D01*
X341190Y181826D01*
X341273Y182159D01*
X341190Y182451D01*
X341023Y182659D01*
X340773Y182826D01*
X340482Y182868D01*
X340232Y182826D01*
X339982Y182659D01*
X339773Y182409D01*
X339690Y182118D01*
X339773Y181784D01*
X340023Y181493D01*
X340398Y181326D01*
X340815Y181284D01*
X341357Y181368D01*
X341648Y181493D01*
X341940Y181701D01*
X342148Y181993D01*
X342190Y182284D01*
X342107Y182576D01*
X341898Y182784D01*
G01X330000Y181700D02*
X334000D01*
Y174300D01*
G01X332550Y210250D02*
X332883Y210292D01*
X333175Y210458D01*
X333425Y210708D01*
X333592Y211000D01*
X333675Y211333D01*
Y211667D01*
X333592Y212000D01*
X333425Y212292D01*
X333175Y212542D01*
X332883Y212708D01*
X332550Y212750D01*
X332217Y212708D01*
X331925Y212542D01*
X331675Y212292D01*
X331508Y212000D01*
X331425Y211667D01*
Y211333D01*
X331508Y211000D01*
X331675Y210708D01*
X331925Y210458D01*
X332217Y210292D01*
X332550Y210250D01*
G01X332217Y210917D02*
X331717Y210250D01*
G01X329450D02*
Y212750D01*
X329950Y212250D01*
G01Y210250D02*
X328950D01*
G01X325000Y209800D02*
Y223200D01*
G01X355194Y21867D02*
Y24367D01*
X354360D01*
X354027Y24242D01*
X353777Y24075D01*
X353569Y23825D01*
X353402Y23534D01*
X353360Y23117D01*
X353402Y22700D01*
X353569Y22409D01*
X353777Y22159D01*
X354027Y21992D01*
X354360Y21867D01*
X355194D01*
G01X352094Y22367D02*
X351844Y22075D01*
X351510Y21909D01*
X351135Y21867D01*
X350802Y21909D01*
X350469Y22117D01*
X350260Y22367D01*
X350219Y22617D01*
X350302Y22909D01*
X350594Y23117D01*
X350885Y23200D01*
X351260D01*
G01X350885D02*
X350635Y23325D01*
X350427Y23534D01*
X350344Y23784D01*
X350427Y24034D01*
X350635Y24242D01*
X351010Y24367D01*
X351385Y24325D01*
X351760Y24159D01*
G01X362900Y32900D02*
X346800D01*
G01X362900Y25900D02*
Y32900D01*
G01X346800Y25900D02*
X362900D01*
G01X346800Y32900D02*
Y25900D01*
G01X345700Y30700D02*
Y17300D01*
G01X362017Y59750D02*
Y57958D01*
X361850Y57583D01*
X361517Y57333D01*
X361100Y57250D01*
X360683Y57333D01*
X360350Y57583D01*
X360183Y57958D01*
Y59750D01*
G01X358000Y57250D02*
Y59750D01*
X358500Y59250D01*
G01Y57250D02*
X357500D01*
G01X355692Y59333D02*
X355442Y59583D01*
X355150Y59708D01*
X354817Y59750D01*
X354400Y59667D01*
X354108Y59458D01*
X354025Y59208D01*
X354067Y58958D01*
X354233Y58750D01*
X355067Y58333D01*
X355442Y58042D01*
X355692Y57625D01*
X355775Y57250D01*
X354025D01*
G01X346631Y55354D02*
X348631Y53354D01*
X350631Y55354D01*
G01X535677Y75611D02*
Y95311D01*
X509577D01*
Y100011D01*
X495777D01*
Y95311D01*
X469677D01*
Y75611D01*
X535677D01*
G01X477600Y103000D02*
Y100500D01*
G01X478558Y103000D02*
X476642D01*
G01X473583Y102792D02*
X473833Y102917D01*
X474125Y103000D01*
X474458D01*
X474833Y102875D01*
X475125Y102667D01*
X475333Y102417D01*
X475500Y102000D01*
X475542Y101625D01*
X475458Y101250D01*
X475333Y101000D01*
X475083Y100750D01*
X474792Y100583D01*
X474500Y100500D01*
X474208D01*
X473917Y100583D01*
X473667Y100708D01*
X473458Y100875D01*
G01X471400Y100500D02*
Y103000D01*
X471900Y102500D01*
G01Y100500D02*
X470900D01*
G01X476683Y106792D02*
X476933Y106917D01*
X477225Y107000D01*
X477558D01*
X477933Y106875D01*
X478225Y106667D01*
X478433Y106417D01*
X478600Y106000D01*
X478642Y105625D01*
X478558Y105250D01*
X478433Y105000D01*
X478183Y104750D01*
X477892Y104583D01*
X477600Y104500D01*
X477308D01*
X477017Y104583D01*
X476767Y104708D01*
X476558Y104875D01*
G01X475292Y106583D02*
X475042Y106833D01*
X474750Y106958D01*
X474417Y107000D01*
X474000Y106917D01*
X473708Y106708D01*
X473625Y106458D01*
X473667Y106208D01*
X473833Y106000D01*
X474667Y105583D01*
X475042Y105292D01*
X475292Y104875D01*
X475375Y104500D01*
X473625D01*
G01X471483D02*
X471400Y105042D01*
X471275Y105500D01*
X471108Y105917D01*
X470900Y106375D01*
X470567Y107000D01*
X472233D01*
G01X505183Y108042D02*
X505433Y108167D01*
X505725Y108250D01*
X506058D01*
X506433Y108125D01*
X506725Y107917D01*
X506933Y107667D01*
X507100Y107250D01*
X507142Y106875D01*
X507058Y106500D01*
X506933Y106250D01*
X506683Y106000D01*
X506392Y105833D01*
X506100Y105750D01*
X505808D01*
X505517Y105833D01*
X505267Y105958D01*
X505058Y106125D01*
G01X503958Y105750D02*
Y108250D01*
X502042Y105750D01*
Y108250D01*
G01X500692Y107833D02*
X500442Y108083D01*
X500150Y108208D01*
X499817Y108250D01*
X499400Y108167D01*
X499108Y107958D01*
X499025Y107708D01*
X499067Y107458D01*
X499233Y107250D01*
X500067Y106833D01*
X500442Y106542D01*
X500692Y106125D01*
X500775Y105750D01*
X499025D01*
G01X535600Y104000D02*
Y101500D01*
G01X536558Y104000D02*
X534642D01*
G01X531583Y103792D02*
X531833Y103917D01*
X532125Y104000D01*
X532458D01*
X532833Y103875D01*
X533125Y103667D01*
X533333Y103417D01*
X533500Y103000D01*
X533542Y102625D01*
X533458Y102250D01*
X533333Y102000D01*
X533083Y101750D01*
X532792Y101583D01*
X532500Y101500D01*
X532208D01*
X531917Y101583D01*
X531667Y101708D01*
X531458Y101875D01*
G01X530192Y103583D02*
X529942Y103833D01*
X529650Y103958D01*
X529317Y104000D01*
X528900Y103917D01*
X528608Y103708D01*
X528525Y103458D01*
X528567Y103208D01*
X528733Y103000D01*
X529567Y102583D01*
X529942Y102292D01*
X530192Y101875D01*
X530275Y101500D01*
X528525D01*
G01X534683Y107792D02*
X534933Y107917D01*
X535225Y108000D01*
X535558D01*
X535933Y107875D01*
X536225Y107667D01*
X536433Y107417D01*
X536600Y107000D01*
X536642Y106625D01*
X536558Y106250D01*
X536433Y106000D01*
X536183Y105750D01*
X535892Y105583D01*
X535600Y105500D01*
X535308D01*
X535017Y105583D01*
X534767Y105708D01*
X534558Y105875D01*
G01X533292Y107583D02*
X533042Y107833D01*
X532750Y107958D01*
X532417Y108000D01*
X532000Y107917D01*
X531708Y107708D01*
X531625Y107458D01*
X531667Y107208D01*
X531833Y107000D01*
X532667Y106583D01*
X533042Y106292D01*
X533292Y105875D01*
X533375Y105500D01*
X531625D01*
G01X529400D02*
X529108Y105542D01*
X528775Y105667D01*
X528567Y105875D01*
X528483Y106167D01*
X528567Y106458D01*
X528817Y106708D01*
X529192Y106833D01*
X529608D01*
X529858Y106917D01*
X530067Y107125D01*
X530150Y107417D01*
X530025Y107708D01*
X529733Y107917D01*
X529400Y108000D01*
X529067Y107917D01*
X528775Y107708D01*
X528650Y107417D01*
X528733Y107125D01*
X528942Y106917D01*
X529192Y106833D01*
X529608D01*
X529983Y106708D01*
X530233Y106458D01*
X530317Y106167D01*
X530233Y105875D01*
X530025Y105667D01*
X529692Y105542D01*
X529400Y105500D01*
G54D17*
G01X290529Y57757D02*
Y56657D01*
G01Y60457D02*
Y59357D01*
G01X310200Y48300D02*
Y44300D01*
M02*
